# S9S_MB_2U (Grand Teton) — schematic netlist excerpt (pin names and nets, part order shuffled) for the footprints in the layout excerpt that follows; sources: Cadence DE-HDL packaged netlist, KiCad conversion of 03242023_DA0F0TMBIJ0_F0T_Motherboard_J_brd_V01_OCP.brd

R618  Q_RES  10K 1% CHIP  pkg 0402LF  page 199 : A = FM_PCH_IO_EXPANDER ; B = GND
PR151  Q_RES  8.87K 1% EMPTY  pkg 0402LF  page 267 : A = PVCCIN_CPU0_LSET1 ; B = GND

(kicad_pcb
	(version 20260206)
	(generator "pcbnew")
	(generator_version "10.0")
	(general
		(thickness 1.6)
		(legacy_teardrops no)
	)
	(paper "A4")
	(title_block
		(title "03242023_DA0F0TMBIJ0_F0T_Motherboard_J_brd_V01_OCP.brd")
		(comment 1 "Grand Teton / footprints 1326-1327 of 6105")
	)
	(layers
		(0 "F.Cu" signal "TOP")
		(4 "In1.Cu" signal "GND")
		(6 "In2.Cu" signal "IN1")
		(8 "In3.Cu" signal "GND1")
		(10 "In4.Cu" signal "IN2")
		(12 "In5.Cu" signal "GND2")
		(14 "In6.Cu" signal "IN3")
		(16 "In7.Cu" signal "GND3")
		(18 "In8.Cu" signal "VCC")
		(20 "In9.Cu" signal "VCC1")
		(22 "In10.Cu" signal "GND4")
		(24 "In11.Cu" signal "IN4")
		(26 "In12.Cu" signal "GND5")
		(28 "In13.Cu" signal "IN5")
		(30 "In14.Cu" signal "GND6")
		(32 "In15.Cu" signal "IN6")
		(34 "In16.Cu" signal "GND7")
		(2 "B.Cu" signal "BOTTOM")
		(9 "F.Adhes" user "F.Adhesive")
		(11 "B.Adhes" user "B.Adhesive")
		(13 "F.Paste" user "Package Geometry/Pastemask Top")
		(15 "B.Paste" user "Package Geometry/Pastemask Bottom")
		(5 "F.SilkS" user "Ref Des/Silkscreen Top")
		(7 "B.SilkS" user "Ref Des/Silkscreen Bottom")
		(1 "F.Mask" user "Board Geometry/Soldermask Top")
		(3 "B.Mask" user "Board Geometry/Soldermask Bottom")
		(17 "Dwgs.User" user "User.Drawings")
		(19 "Cmts.User" user "User.Comments")
		(21 "Eco1.User" user "User.Eco1")
		(23 "Eco2.User" user "User.Eco2")
		(25 "Edge.Cuts" user "Board Geometry/Outline")
		(27 "Margin" user)
		(31 "F.CrtYd" user "Package Geometry/Place Bound Top")
		(29 "B.CrtYd" user "Package Geometry/Place Bound Bottom")
		(35 "F.Fab" user "Ref Des/Assembly Top")
		(33 "B.Fab" user "Ref Des/Assembly Bottom")
	)
	(footprint ""
		(layer "F.Cu")
		(at 317.396622 -57.775348 180)
		(property "Reference" "R618"
			(at 0 0 180)
			(layer "F.SilkS")
			(hide yes)
			(effects
				(font
					(size 1.27 1.27)
				)
			)
		)
		(property "Value" ""
			(at 0 0 180)
			(layer "F.Fab")
			(effects
				(font
					(size 1.27 1.27)
				)
			)
		)
		(duplicate_pad_numbers_are_jumpers no)
		(fp_line
			(start 0.7874 0.4064)
			(end -0.7874 0.4064)
			(stroke
				(width 0.1524)
				(type default)
			)
			(layer "F.SilkS")
		)
		(fp_line
			(start 0.7874 -0.4064)
			(end 0.7874 0.4064)
			(stroke
				(width 0.1524)
				(type default)
			)
			(layer "F.SilkS")
		)
		(fp_line
			(start -0.7874 0.4064)
			(end -0.7874 -0.4064)
			(stroke
				(width 0.1524)
				(type default)
			)
			(layer "F.SilkS")
		)
		(fp_line
			(start -0.7874 -0.4064)
			(end 0.7874 -0.4064)
			(stroke
				(width 0.1524)
				(type default)
			)
			(layer "F.SilkS")
		)
		(fp_line
			(start 0.67945 0.3048)
			(end 0.120396 0.3048)
			(stroke
				(width 0.1)
				(type default)
			)
			(layer "F.Fab")
		)
		(fp_line
			(start 0.67945 -0.3048)
			(end 0.67945 0.3048)
			(stroke
				(width 0.1)
				(type default)
			)
			(layer "F.Fab")
		)
		(fp_line
			(start 0.12065 -0.2794)
			(end 0.12065 -0.3048)
			(stroke
				(width 0.1)
				(type default)
			)
			(layer "F.Fab")
		)
		(fp_line
			(start 0.12065 -0.3048)
			(end 0.67945 -0.3048)
			(stroke
				(width 0.1)
				(type default)
			)
			(layer "F.Fab")
		)
		(fp_line
			(start 0.120396 0.3048)
			(end 0.120396 0.2794)
			(stroke
				(width 0.1)
				(type default)
			)
			(layer "F.Fab")
		)
		(fp_line
			(start 0.120396 0.2794)
			(end -0.12065 0.2794)
			(stroke
				(width 0.1)
				(type default)
			)
			(layer "F.Fab")
		)
		(fp_line
			(start -0.12065 0.3048)
			(end -0.67945 0.3048)
			(stroke
				(width 0.1)
				(type default)
			)
			(layer "F.Fab")
		)
		(fp_line
			(start -0.12065 0.2794)
			(end -0.12065 0.3048)
			(stroke
				(width 0.1)
				(type default)
			)
			(layer "F.Fab")
		)
		(fp_line
			(start -0.12065 -0.2794)
			(end 0.12065 -0.2794)
			(stroke
				(width 0.1)
				(type default)
			)
			(layer "F.Fab")
		)
		(fp_line
			(start -0.12065 -0.305054)
			(end -0.12065 -0.2794)
			(stroke
				(width 0.1)
				(type default)
			)
			(layer "F.Fab")
		)
		(fp_line
			(start -0.67945 0.3048)
			(end -0.67945 -0.305054)
			(stroke
				(width 0.1)
				(type default)
			)
			(layer "F.Fab")
		)
		(fp_line
			(start -0.67945 -0.305054)
			(end -0.12065 -0.305054)
			(stroke
				(width 0.1)
				(type default)
			)
			(layer "F.Fab")
		)
		(pad "1" smd circle
			(at -0.40005 0 180)
			(size 0 0)
			(layers "F.Cu" "F.Mask" "F.Paste")
			(net "FM_PCH_IO_EXPANDER")
		)
		(pad "2" smd circle
			(at 0.40005 0 180)
			(size 0 0)
			(layers "F.Cu" "F.Mask" "F.Paste")
			(net "GND")
		)
	)
	(footprint ""
		(layer "F.Cu")
		(at 343.646252 -338.86013)
		(property "Reference" "PR151"
			(at 0 0 0)
			(layer "F.SilkS")
			(hide yes)
			(effects
				(font
					(size 1.27 1.27)
				)
			)
		)
		(property "Value" ""
			(at 0 0 0)
			(layer "F.Fab")
			(effects
				(font
					(size 1.27 1.27)
				)
			)
		)
		(duplicate_pad_numbers_are_jumpers no)
		(fp_line
			(start -0.7874 -0.4064)
			(end 0.7874 -0.4064)
			(stroke
				(width 0.1524)
				(type default)
			)
			(layer "F.SilkS")
		)
		(fp_line
			(start -0.7874 0.4064)
			(end -0.7874 -0.4064)
			(stroke
				(width 0.1524)
				(type default)
			)
			(layer "F.SilkS")
		)
		(fp_line
			(start 0.7874 -0.4064)
			(end 0.7874 0.4064)
			(stroke
				(width 0.1524)
				(type default)
			)
			(layer "F.SilkS")
		)
		(fp_line
			(start 0.7874 0.4064)
			(end -0.7874 0.4064)
			(stroke
				(width 0.1524)
				(type default)
			)
			(layer "F.SilkS")
		)
		(fp_line
			(start -0.67945 -0.305054)
			(end -0.12065 -0.305054)
			(stroke
				(width 0.1)
				(type default)
			)
			(layer "F.Fab")
		)
		(fp_line
			(start -0.67945 0.3048)
			(end -0.67945 -0.305054)
			(stroke
				(width 0.1)
				(type default)
			)
			(layer "F.Fab")
		)
		(fp_line
			(start -0.12065 -0.305054)
			(end -0.12065 -0.2794)
			(stroke
				(width 0.1)
				(type default)
			)
			(layer "F.Fab")
		)
		(fp_line
			(start -0.12065 -0.2794)
			(end 0.12065 -0.2794)
			(stroke
				(width 0.1)
				(type default)
			)
			(layer "F.Fab")
		)
		(fp_line
			(start -0.12065 0.2794)
			(end -0.12065 0.3048)
			(stroke
				(width 0.1)
				(type default)
			)
			(layer "F.Fab")
		)
		(fp_line
			(start -0.12065 0.3048)
			(end -0.67945 0.3048)
			(stroke
				(width 0.1)
				(type default)
			)
			(layer "F.Fab")
		)
		(fp_line
			(start 0.120396 0.2794)
			(end -0.12065 0.2794)
			(stroke
				(width 0.1)
				(type default)
			)
			(layer "F.Fab")
		)
		(fp_line
			(start 0.120396 0.3048)
			(end 0.120396 0.2794)
			(stroke
				(width 0.1)
				(type default)
			)
			(layer "F.Fab")
		)
		(fp_line
			(start 0.12065 -0.3048)
			(end 0.67945 -0.3048)
			(stroke
				(width 0.1)
				(type default)
			)
			(layer "F.Fab")
		)
		(fp_line
			(start 0.12065 -0.2794)
			(end 0.12065 -0.3048)
			(stroke
				(width 0.1)
				(type default)
			)
			(layer "F.Fab")
		)
		(fp_line
			(start 0.67945 -0.3048)
			(end 0.67945 0.3048)
			(stroke
				(width 0.1)
				(type default)
			)
			(layer "F.Fab")
		)
		(fp_line
			(start 0.67945 0.3048)
			(end 0.120396 0.3048)
			(stroke
				(width 0.1)
				(type default)
			)
			(layer "F.Fab")
		)
		(pad "1" smd circle
			(at -0.40005 0)
			(size 0 0)
			(layers "F.Cu" "F.Mask" "F.Paste")
			(net "PVCCIN_CPU0_LSET1")
		)
		(pad "2" smd circle
			(at 0.40005 0)
			(size 0 0)
			(layers "F.Cu" "F.Mask" "F.Paste")
			(net "GND")
		)
	)
)
